(kicad_pcb
	(version 20260206)
	(generator "pcbnew")
	(generator_version "10.0")
	(general
		(thickness 1.6)
		(legacy_teardrops no)
	)
	(paper "A4")
	(title_block
		(title "03242023_DA0F0TMBIJ0_F0T_Motherboard_J_brd_V01_OCP.brd")
		(comment 1 "Grand Teton / footprints 3914-3919 of 6105")
	)
	(layers
		(0 "F.Cu" signal "TOP")
		(4 "In1.Cu" signal "GND")
		(6 "In2.Cu" signal "IN1")
		(8 "In3.Cu" signal "GND1")
		(10 "In4.Cu" signal "IN2")
		(12 "In5.Cu" signal "GND2")
		(14 "In6.Cu" signal "IN3")
		(16 "In7.Cu" signal "GND3")
		(18 "In8.Cu" signal "VCC")
		(20 "In9.Cu" signal "VCC1")
		(22 "In10.Cu" signal "GND4")
		(24 "In11.Cu" signal "IN4")
		(26 "In12.Cu" signal "GND5")
		(28 "In13.Cu" signal "IN5")
		(30 "In14.Cu" signal "GND6")
		(32 "In15.Cu" signal "IN6")
		(34 "In16.Cu" signal "GND7")
		(2 "B.Cu" signal "BOTTOM")
		(9 "F.Adhes" user "F.Adhesive")
		(11 "B.Adhes" user "B.Adhesive")
		(13 "F.Paste" user "Package Geometry/Pastemask Top")
		(15 "B.Paste" user "Package Geometry/Pastemask Bottom")
		(5 "F.SilkS" user "Ref Des/Silkscreen Top")
		(7 "B.SilkS" user "Ref Des/Silkscreen Bottom")
		(1 "F.Mask" user "Board Geometry/Soldermask Top")
		(3 "B.Mask" user "Board Geometry/Soldermask Bottom")
		(17 "Dwgs.User" user "User.Drawings")
		(19 "Cmts.User" user "User.Comments")
		(21 "Eco1.User" user "User.Eco1")
		(23 "Eco2.User" user "User.Eco2")
		(25 "Edge.Cuts" user "Board Geometry/Outline")
		(27 "Margin" user)
		(31 "F.CrtYd" user "Package Geometry/Place Bound Top")
		(29 "B.CrtYd" user "Package Geometry/Place Bound Bottom")
		(35 "F.Fab" user "Ref Des/Assembly Top")
		(33 "B.Fab" user "Ref Des/Assembly Bottom")
	)
	(footprint ""
		(layer "F.Cu")
		(at 230.248206 -247.684036 180)
		(property "Reference" "R3337"
			(at 0 0 180)
			(layer "F.SilkS")
			(hide yes)
			(effects
				(font
					(size 1.27 1.27)
				)
			)
		)
		(property "Value" ""
			(at 0 0 180)
			(layer "F.Fab")
			(effects
				(font
					(size 1.27 1.27)
				)
			)
		)
		(duplicate_pad_numbers_are_jumpers no)
		(fp_line
			(start 0.7874 0.4064)
			(end -0.7874 0.4064)
			(stroke
				(width 0.1524)
				(type default)
			)
			(layer "F.SilkS")
		)
		(fp_line
			(start 0.7874 -0.4064)
			(end 0.7874 0.4064)
			(stroke
				(width 0.1524)
				(type default)
			)
			(layer "F.SilkS")
		)
		(fp_line
			(start -0.7874 0.4064)
			(end -0.7874 -0.4064)
			(stroke
				(width 0.1524)
				(type default)
			)
			(layer "F.SilkS")
		)
		(fp_line
			(start -0.7874 -0.4064)
			(end 0.7874 -0.4064)
			(stroke
				(width 0.1524)
				(type default)
			)
			(layer "F.SilkS")
		)
		(fp_line
			(start 0.67945 0.3048)
			(end 0.120396 0.3048)
			(stroke
				(width 0.1)
				(type default)
			)
			(layer "F.Fab")
		)
		(fp_line
			(start 0.67945 -0.3048)
			(end 0.67945 0.3048)
			(stroke
				(width 0.1)
				(type default)
			)
			(layer "F.Fab")
		)
		(fp_line
			(start 0.12065 -0.2794)
			(end 0.12065 -0.3048)
			(stroke
				(width 0.1)
				(type default)
			)
			(layer "F.Fab")
		)
		(fp_line
			(start 0.12065 -0.3048)
			(end 0.67945 -0.3048)
			(stroke
				(width 0.1)
				(type default)
			)
			(layer "F.Fab")
		)
		(fp_line
			(start 0.120396 0.3048)
			(end 0.120396 0.2794)
			(stroke
				(width 0.1)
				(type default)
			)
			(layer "F.Fab")
		)
		(fp_line
			(start 0.120396 0.2794)
			(end -0.12065 0.2794)
			(stroke
				(width 0.1)
				(type default)
			)
			(layer "F.Fab")
		)
		(fp_line
			(start -0.12065 0.3048)
			(end -0.67945 0.3048)
			(stroke
				(width 0.1)
				(type default)
			)
			(layer "F.Fab")
		)
		(fp_line
			(start -0.12065 0.2794)
			(end -0.12065 0.3048)
			(stroke
				(width 0.1)
				(type default)
			)
			(layer "F.Fab")
		)
		(fp_line
			(start -0.12065 -0.2794)
			(end 0.12065 -0.2794)
			(stroke
				(width 0.1)
				(type default)
			)
			(layer "F.Fab")
		)
		(fp_line
			(start -0.12065 -0.305054)
			(end -0.12065 -0.2794)
			(stroke
				(width 0.1)
				(type default)
			)
			(layer "F.Fab")
		)
		(fp_line
			(start -0.67945 0.3048)
			(end -0.67945 -0.305054)
			(stroke
				(width 0.1)
				(type default)
			)
			(layer "F.Fab")
		)
		(fp_line
			(start -0.67945 -0.305054)
			(end -0.12065 -0.305054)
			(stroke
				(width 0.1)
				(type default)
			)
			(layer "F.Fab")
		)
		(pad "1" smd circle
			(at -0.40005 0 180)
			(size 0 0)
			(layers "F.Cu" "F.Mask" "F.Paste")
			(net "CLK_100M_GPU_FPGA_DP_R")
		)
		(pad "2" smd circle
			(at 0.40005 0 180)
			(size 0 0)
			(layers "F.Cu" "F.Mask" "F.Paste")
			(net "CLK_100M_GPU_FPGA_DP")
		)
	)
	(footprint ""
		(layer "F.Cu")
		(at 299.02023 -49.320196 180)
		(property "Reference" "R2241"
			(at 0 0 180)
			(layer "F.SilkS")
			(hide yes)
			(effects
				(font
					(size 1.27 1.27)
				)
			)
		)
		(property "Value" ""
			(at 0 0 180)
			(layer "F.Fab")
			(effects
				(font
					(size 1.27 1.27)
				)
			)
		)
		(duplicate_pad_numbers_are_jumpers no)
		(fp_line
			(start 0.7874 0.4064)
			(end -0.7874 0.4064)
			(stroke
				(width 0.1524)
				(type default)
			)
			(layer "F.SilkS")
		)
		(fp_line
			(start 0.7874 -0.4064)
			(end 0.7874 0.4064)
			(stroke
				(width 0.1524)
				(type default)
			)
			(layer "F.SilkS")
		)
		(fp_line
			(start -0.7874 0.4064)
			(end -0.7874 -0.4064)
			(stroke
				(width 0.1524)
				(type default)
			)
			(layer "F.SilkS")
		)
		(fp_line
			(start -0.7874 -0.4064)
			(end 0.7874 -0.4064)
			(stroke
				(width 0.1524)
				(type default)
			)
			(layer "F.SilkS")
		)
		(fp_line
			(start 0.67945 0.3048)
			(end 0.120396 0.3048)
			(stroke
				(width 0.1)
				(type default)
			)
			(layer "F.Fab")
		)
		(fp_line
			(start 0.67945 -0.3048)
			(end 0.67945 0.3048)
			(stroke
				(width 0.1)
				(type default)
			)
			(layer "F.Fab")
		)
		(fp_line
			(start 0.12065 -0.2794)
			(end 0.12065 -0.3048)
			(stroke
				(width 0.1)
				(type default)
			)
			(layer "F.Fab")
		)
		(fp_line
			(start 0.12065 -0.3048)
			(end 0.67945 -0.3048)
			(stroke
				(width 0.1)
				(type default)
			)
			(layer "F.Fab")
		)
		(fp_line
			(start 0.120396 0.3048)
			(end 0.120396 0.2794)
			(stroke
				(width 0.1)
				(type default)
			)
			(layer "F.Fab")
		)
		(fp_line
			(start 0.120396 0.2794)
			(end -0.12065 0.2794)
			(stroke
				(width 0.1)
				(type default)
			)
			(layer "F.Fab")
		)
		(fp_line
			(start -0.12065 0.3048)
			(end -0.67945 0.3048)
			(stroke
				(width 0.1)
				(type default)
			)
			(layer "F.Fab")
		)
		(fp_line
			(start -0.12065 0.2794)
			(end -0.12065 0.3048)
			(stroke
				(width 0.1)
				(type default)
			)
			(layer "F.Fab")
		)
		(fp_line
			(start -0.12065 -0.2794)
			(end 0.12065 -0.2794)
			(stroke
				(width 0.1)
				(type default)
			)
			(layer "F.Fab")
		)
		(fp_line
			(start -0.12065 -0.305054)
			(end -0.12065 -0.2794)
			(stroke
				(width 0.1)
				(type default)
			)
			(layer "F.Fab")
		)
		(fp_line
			(start -0.67945 0.3048)
			(end -0.67945 -0.305054)
			(stroke
				(width 0.1)
				(type default)
			)
			(layer "F.Fab")
		)
		(fp_line
			(start -0.67945 -0.305054)
			(end -0.12065 -0.305054)
			(stroke
				(width 0.1)
				(type default)
			)
			(layer "F.Fab")
		)
		(pad "1" smd circle
			(at -0.40005 0 180)
			(size 0 0)
			(layers "F.Cu" "F.Mask" "F.Paste")
			(net "FM_BOARD_SKU_ID1")
		)
		(pad "2" smd circle
			(at 0.40005 0 180)
			(size 0 0)
			(layers "F.Cu" "F.Mask" "F.Paste")
			(net "GND")
		)
	)
	(footprint ""
		(layer "F.Cu")
		(at 130.10388 -96.230948 -90)
		(property "Reference" "Q143"
			(at -2.479802 0.69088 0)
			(unlocked yes)
			(layer "F.SilkS")
			(effects
				(font
					(size 0.635 0.4064)
					(thickness 0.1524)
				)
			)
		)
		(property "Value" ""
			(at 0 0 270)
			(layer "F.Fab")
			(effects
				(font
					(size 1.27 1.27)
				)
			)
		)
		(duplicate_pad_numbers_are_jumpers no)
		(fp_line
			(start -1.376172 1.199896)
			(end -1.376172 -1.199896)
			(stroke
				(width 0.1524)
				(type default)
			)
			(layer "F.SilkS")
		)
		(fp_line
			(start 1.376172 1.199896)
			(end -1.376172 1.199896)
			(stroke
				(width 0.1524)
				(type default)
			)
			(layer "F.SilkS")
		)
		(fp_line
			(start 0 -0.762)
			(end 0.508 -1.199896)
			(stroke
				(width 0.1524)
				(type default)
			)
			(layer "F.SilkS")
		)
		(fp_line
			(start -1.376172 -1.199896)
			(end -0.508 -1.199896)
			(stroke
				(width 0.1524)
				(type default)
			)
			(layer "F.SilkS")
		)
		(fp_line
			(start -0.508 -1.199896)
			(end 0 -0.762)
			(stroke
				(width 0.1524)
				(type default)
			)
			(layer "F.SilkS")
		)
		(fp_line
			(start 0.508 -1.199896)
			(end 1.376172 -1.199896)
			(stroke
				(width 0.1524)
				(type default)
			)
			(layer "F.SilkS")
		)
		(fp_line
			(start 1.376172 -1.199896)
			(end 1.376172 1.199896)
			(stroke
				(width 0.1524)
				(type default)
			)
			(layer "F.SilkS")
		)
		(fp_poly
			(pts
				(xy -1.5875 -0.8763) (xy -2.3495 -1.2573) (xy -2.3495 -0.4953)
			)
			(stroke
				(width 0)
				(type default)
			)
			(fill yes)
			(layer "F.SilkS")
		)
		(fp_line
			(start -0.674878 1.100074)
			(end -0.674878 -1.100074)
			(stroke
				(width 0.1)
				(type default)
			)
			(layer "F.Fab")
		)
		(fp_line
			(start 0.674878 1.100074)
			(end -0.674878 1.100074)
			(stroke
				(width 0.1)
				(type default)
			)
			(layer "F.Fab")
		)
		(fp_line
			(start -0.674878 -1.100074)
			(end 0.674878 -1.100074)
			(stroke
				(width 0.1)
				(type default)
			)
			(layer "F.Fab")
		)
		(fp_line
			(start 0.674878 -1.100074)
			(end 0.674878 1.100074)
			(stroke
				(width 0.1)
				(type default)
			)
			(layer "F.Fab")
		)
		(fp_poly
			(pts
				(xy -1.4605 -0.7493) (xy -2.2225 -1.1303) (xy -2.2225 -0.3683)
			)
			(stroke
				(width 0)
				(type default)
			)
			(fill yes)
			(layer "F.Fab")
		)
		(pad "1" smd rect
			(at -0.899922 -0.750062 180)
			(size 0.6096 0.6096)
			(layers "F.Cu" "F.Mask" "F.Paste")
			(net "GND")
		)
		(pad "2" smd rect
			(at -0.899922 0 180)
			(size 0.4064 0.6096)
			(layers "F.Cu" "F.Mask" "F.Paste")
			(net "H_CPU0_MEMHOT_OUT_R")
		)
		(pad "3" smd rect
			(at -0.899922 0.750062 180)
			(size 0.6096 0.6096)
			(layers "F.Cu" "F.Mask" "F.Paste")
			(net "H_CPU0_MEMHOT_OUT")
		)
		(pad "4" smd rect
			(at 0.899922 0.750062 180)
			(size 0.6096 0.6096)
			(layers "F.Cu" "F.Mask" "F.Paste")
			(net "PVNN_TERM_CPU0")
		)
		(pad "5" smd rect
			(at 0.899922 0 180)
			(size 0.4064 0.6096)
			(layers "F.Cu" "F.Mask" "F.Paste")
			(net "H_CPU0_MEMHOT_OUT_VT_R_N")
		)
		(pad "6" smd rect
			(at 0.899922 -0.750062 180)
			(size 0.6096 0.6096)
			(layers "F.Cu" "F.Mask" "F.Paste")
			(net "H_CPU0_MEMHOT_OUT_VT_N")
		)
	)
	(footprint ""
		(layer "F.Cu")
		(at 225.171762 -71.192898 90)
		(property "Reference" "R3977"
			(at 0 0 90)
			(layer "F.SilkS")
			(hide yes)
			(effects
				(font
					(size 1.27 1.27)
				)
			)
		)
		(property "Value" ""
			(at 0 0 90)
			(layer "F.Fab")
			(effects
				(font
					(size 1.27 1.27)
				)
			)
		)
		(duplicate_pad_numbers_are_jumpers no)
		(fp_line
			(start 0.7874 -0.4064)
			(end 0.7874 0.4064)
			(stroke
				(width 0.1524)
				(type default)
			)
			(layer "F.SilkS")
		)
		(fp_line
			(start -0.7874 -0.4064)
			(end 0.7874 -0.4064)
			(stroke
				(width 0.1524)
				(type default)
			)
			(layer "F.SilkS")
		)
		(fp_line
			(start 0.7874 0.4064)
			(end -0.7874 0.4064)
			(stroke
				(width 0.1524)
				(type default)
			)
			(layer "F.SilkS")
		)
		(fp_line
			(start -0.7874 0.4064)
			(end -0.7874 -0.4064)
			(stroke
				(width 0.1524)
				(type default)
			)
			(layer "F.SilkS")
		)
		(fp_line
			(start -0.12065 -0.305054)
			(end -0.12065 -0.2794)
			(stroke
				(width 0.1)
				(type default)
			)
			(layer "F.Fab")
		)
		(fp_line
			(start -0.67945 -0.305054)
			(end -0.12065 -0.305054)
			(stroke
				(width 0.1)
				(type default)
			)
			(layer "F.Fab")
		)
		(fp_line
			(start 0.67945 -0.3048)
			(end 0.67945 0.3048)
			(stroke
				(width 0.1)
				(type default)
			)
			(layer "F.Fab")
		)
		(fp_line
			(start 0.12065 -0.3048)
			(end 0.67945 -0.3048)
			(stroke
				(width 0.1)
				(type default)
			)
			(layer "F.Fab")
		)
		(fp_line
			(start 0.12065 -0.2794)
			(end 0.12065 -0.3048)
			(stroke
				(width 0.1)
				(type default)
			)
			(layer "F.Fab")
		)
		(fp_line
			(start -0.12065 -0.2794)
			(end 0.12065 -0.2794)
			(stroke
				(width 0.1)
				(type default)
			)
			(layer "F.Fab")
		)
		(fp_line
			(start 0.120396 0.2794)
			(end -0.12065 0.2794)
			(stroke
				(width 0.1)
				(type default)
			)
			(layer "F.Fab")
		)
		(fp_line
			(start -0.12065 0.2794)
			(end -0.12065 0.3048)
			(stroke
				(width 0.1)
				(type default)
			)
			(layer "F.Fab")
		)
		(fp_line
			(start 0.67945 0.3048)
			(end 0.120396 0.3048)
			(stroke
				(width 0.1)
				(type default)
			)
			(layer "F.Fab")
		)
		(fp_line
			(start 0.120396 0.3048)
			(end 0.120396 0.2794)
			(stroke
				(width 0.1)
				(type default)
			)
			(layer "F.Fab")
		)
		(fp_line
			(start -0.12065 0.3048)
			(end -0.67945 0.3048)
			(stroke
				(width 0.1)
				(type default)
			)
			(layer "F.Fab")
		)
		(fp_line
			(start -0.67945 0.3048)
			(end -0.67945 -0.305054)
			(stroke
				(width 0.1)
				(type default)
			)
			(layer "F.Fab")
		)
		(pad "1" smd circle
			(at -0.40005 0 90)
			(size 0 0)
			(layers "F.Cu" "F.Mask" "F.Paste")
			(net "P3V3_AUX")
		)
		(pad "2" smd circle
			(at 0.40005 0 90)
			(size 0 0)
			(layers "F.Cu" "F.Mask" "F.Paste")
			(net "P3V3_E1S_FAULT_0")
		)
	)
	(footprint ""
		(layer "F.Cu")
		(at 152.075896 -38.575234 90)
		(property "Reference" "C2326"
			(at 0 0 90)
			(layer "F.SilkS")
			(hide yes)
			(effects
				(font
					(size 1.27 1.27)
				)
			)
		)
		(property "Value" ""
			(at 0 0 90)
			(layer "F.Fab")
			(effects
				(font
					(size 1.27 1.27)
				)
			)
		)
		(duplicate_pad_numbers_are_jumpers no)
		(fp_line
			(start 0.7874 -0.4064)
			(end 0.7874 0.4064)
			(stroke
				(width 0.1524)
				(type default)
			)
			(layer "F.SilkS")
		)
		(fp_line
			(start -0.7874 -0.4064)
			(end 0.7874 -0.4064)
			(stroke
				(width 0.1524)
				(type default)
			)
			(layer "F.SilkS")
		)
		(fp_line
			(start 0.7874 0.4064)
			(end -0.7874 0.4064)
			(stroke
				(width 0.1524)
				(type default)
			)
			(layer "F.SilkS")
		)
		(fp_line
			(start -0.7874 0.4064)
			(end -0.7874 -0.4064)
			(stroke
				(width 0.1524)
				(type default)
			)
			(layer "F.SilkS")
		)
		(fp_line
			(start -0.12065 -0.305054)
			(end -0.12065 -0.2794)
			(stroke
				(width 0.1)
				(type default)
			)
			(layer "F.Fab")
		)
		(fp_line
			(start -0.67945 -0.305054)
			(end -0.12065 -0.305054)
			(stroke
				(width 0.1)
				(type default)
			)
			(layer "F.Fab")
		)
		(fp_line
			(start 0.67945 -0.3048)
			(end 0.67945 0.3048)
			(stroke
				(width 0.1)
				(type default)
			)
			(layer "F.Fab")
		)
		(fp_line
			(start 0.12065 -0.3048)
			(end 0.67945 -0.3048)
			(stroke
				(width 0.1)
				(type default)
			)
			(layer "F.Fab")
		)
		(fp_line
			(start 0.12065 -0.2794)
			(end 0.12065 -0.3048)
			(stroke
				(width 0.1)
				(type default)
			)
			(layer "F.Fab")
		)
		(fp_line
			(start -0.12065 -0.2794)
			(end 0.12065 -0.2794)
			(stroke
				(width 0.1)
				(type default)
			)
			(layer "F.Fab")
		)
		(fp_line
			(start 0.120396 0.2794)
			(end -0.12065 0.2794)
			(stroke
				(width 0.1)
				(type default)
			)
			(layer "F.Fab")
		)
		(fp_line
			(start -0.12065 0.2794)
			(end -0.12065 0.3048)
			(stroke
				(width 0.1)
				(type default)
			)
			(layer "F.Fab")
		)
		(fp_line
			(start 0.67945 0.3048)
			(end 0.120396 0.3048)
			(stroke
				(width 0.1)
				(type default)
			)
			(layer "F.Fab")
		)
		(fp_line
			(start 0.120396 0.3048)
			(end 0.120396 0.2794)
			(stroke
				(width 0.1)
				(type default)
			)
			(layer "F.Fab")
		)
		(fp_line
			(start -0.12065 0.3048)
			(end -0.67945 0.3048)
			(stroke
				(width 0.1)
				(type default)
			)
			(layer "F.Fab")
		)
		(fp_line
			(start -0.67945 0.3048)
			(end -0.67945 -0.305054)
			(stroke
				(width 0.1)
				(type default)
			)
			(layer "F.Fab")
		)
		(pad "1" smd circle
			(at -0.40005 0 90)
			(size 0 0)
			(layers "F.Cu" "F.Mask" "F.Paste")
			(net "USB_HUB_2_XTAL_IN")
		)
		(pad "2" smd circle
			(at 0.40005 0 90)
			(size 0 0)
			(layers "F.Cu" "F.Mask" "F.Paste")
			(net "GND")
		)
	)
	(footprint ""
		(layer "F.Cu")
		(at 218.08948 -125.8062 180)
		(property "Reference" "R4807"
			(at 0 0 180)
			(layer "F.SilkS")
			(hide yes)
			(effects
				(font
					(size 1.27 1.27)
				)
			)
		)
		(property "Value" ""
			(at 0 0 180)
			(layer "F.Fab")
			(effects
				(font
					(size 1.27 1.27)
				)
			)
		)
		(duplicate_pad_numbers_are_jumpers no)
		(fp_line
			(start 0.7874 0.4064)
			(end -0.7874 0.4064)
			(stroke
				(width 0.1524)
				(type default)
			)
			(layer "F.SilkS")
		)
		(fp_line
			(start 0.7874 -0.4064)
			(end 0.7874 0.4064)
			(stroke
				(width 0.1524)
				(type default)
			)
			(layer "F.SilkS")
		)
		(fp_line
			(start -0.7874 0.4064)
			(end -0.7874 -0.4064)
			(stroke
				(width 0.1524)
				(type default)
			)
			(layer "F.SilkS")
		)
		(fp_line
			(start -0.7874 -0.4064)
			(end 0.7874 -0.4064)
			(stroke
				(width 0.1524)
				(type default)
			)
			(layer "F.SilkS")
		)
		(fp_line
			(start 0.67945 0.3048)
			(end 0.120396 0.3048)
			(stroke
				(width 0.1)
				(type default)
			)
			(layer "F.Fab")
		)
		(fp_line
			(start 0.67945 -0.3048)
			(end 0.67945 0.3048)
			(stroke
				(width 0.1)
				(type default)
			)
			(layer "F.Fab")
		)
		(fp_line
			(start 0.12065 -0.2794)
			(end 0.12065 -0.3048)
			(stroke
				(width 0.1)
				(type default)
			)
			(layer "F.Fab")
		)
		(fp_line
			(start 0.12065 -0.3048)
			(end 0.67945 -0.3048)
			(stroke
				(width 0.1)
				(type default)
			)
			(layer "F.Fab")
		)
		(fp_line
			(start 0.120396 0.3048)
			(end 0.120396 0.2794)
			(stroke
				(width 0.1)
				(type default)
			)
			(layer "F.Fab")
		)
		(fp_line
			(start 0.120396 0.2794)
			(end -0.12065 0.2794)
			(stroke
				(width 0.1)
				(type default)
			)
			(layer "F.Fab")
		)
		(fp_line
			(start -0.12065 0.3048)
			(end -0.67945 0.3048)
			(stroke
				(width 0.1)
				(type default)
			)
			(layer "F.Fab")
		)
		(fp_line
			(start -0.12065 0.2794)
			(end -0.12065 0.3048)
			(stroke
				(width 0.1)
				(type default)
			)
			(layer "F.Fab")
		)
		(fp_line
			(start -0.12065 -0.2794)
			(end 0.12065 -0.2794)
			(stroke
				(width 0.1)
				(type default)
			)
			(layer "F.Fab")
		)
		(fp_line
			(start -0.12065 -0.305054)
			(end -0.12065 -0.2794)
			(stroke
				(width 0.1)
				(type default)
			)
			(layer "F.Fab")
		)
		(fp_line
			(start -0.67945 0.3048)
			(end -0.67945 -0.305054)
			(stroke
				(width 0.1)
				(type default)
			)
			(layer "F.Fab")
		)
		(fp_line
			(start -0.67945 -0.305054)
			(end -0.12065 -0.305054)
			(stroke
				(width 0.1)
				(type default)
			)
			(layer "F.Fab")
		)
		(pad "1" smd circle
			(at -0.40005 0 180)
			(size 0 0)
			(layers "F.Cu" "F.Mask" "F.Paste")
			(net "PWRGD_DSW_PWROK_R1")
		)
		(pad "2" smd circle
			(at 0.40005 0 180)
			(size 0 0)
			(layers "F.Cu" "F.Mask" "F.Paste")
			(net "PWRGD_DSW_PWROK_R2")
		)
	)
)
